# S9S_MB_2U (Grand Teton) — schematic netlist excerpt (pin names and nets, part order shuffled) for the footprints in the layout excerpt that follows; sources: Cadence DE-HDL packaged netlist, KiCad conversion of 03242023_DA0F0TMBIJ0_F0T_Motherboard_J_brd_V01_OCP.brd

C1797  Q_CAP  0.1UF 25V 10% X7R  pkg 0402  page 301 : A = PDB_PRSNT_N ; B = GND
C3266  Q_CAP  1000PF 50V 5% EMPTY  pkg 0402  page 266 : A = PWRGD_PVCCIN_CPU0_R ; B = GND

(kicad_pcb
	(version 20260206)
	(generator "pcbnew")
	(generator_version "10.0")
	(general
		(thickness 1.6)
		(legacy_teardrops no)
	)
	(paper "A4")
	(title_block
		(title "03242023_DA0F0TMBIJ0_F0T_Motherboard_J_brd_V01_OCP.brd")
		(comment 1 "Grand Teton / footprints 2865-2866 of 6105")
	)
	(layers
		(0 "F.Cu" signal "TOP")
		(4 "In1.Cu" signal "GND")
		(6 "In2.Cu" signal "IN1")
		(8 "In3.Cu" signal "GND1")
		(10 "In4.Cu" signal "IN2")
		(12 "In5.Cu" signal "GND2")
		(14 "In6.Cu" signal "IN3")
		(16 "In7.Cu" signal "GND3")
		(18 "In8.Cu" signal "VCC")
		(20 "In9.Cu" signal "VCC1")
		(22 "In10.Cu" signal "GND4")
		(24 "In11.Cu" signal "IN4")
		(26 "In12.Cu" signal "GND5")
		(28 "In13.Cu" signal "IN5")
		(30 "In14.Cu" signal "GND6")
		(32 "In15.Cu" signal "IN6")
		(34 "In16.Cu" signal "GND7")
		(2 "B.Cu" signal "BOTTOM")
		(9 "F.Adhes" user "F.Adhesive")
		(11 "B.Adhes" user "B.Adhesive")
		(13 "F.Paste" user "Package Geometry/Pastemask Top")
		(15 "B.Paste" user "Package Geometry/Pastemask Bottom")
		(5 "F.SilkS" user "Ref Des/Silkscreen Top")
		(7 "B.SilkS" user "Ref Des/Silkscreen Bottom")
		(1 "F.Mask" user "Board Geometry/Soldermask Top")
		(3 "B.Mask" user "Board Geometry/Soldermask Bottom")
		(17 "Dwgs.User" user "User.Drawings")
		(19 "Cmts.User" user "User.Comments")
		(21 "Eco1.User" user "User.Eco1")
		(23 "Eco2.User" user "User.Eco2")
		(25 "Edge.Cuts" user "Board Geometry/Outline")
		(27 "Margin" user)
		(31 "F.CrtYd" user "Package Geometry/Place Bound Top")
		(29 "B.CrtYd" user "Package Geometry/Place Bound Bottom")
		(35 "F.Fab" user "Ref Des/Assembly Top")
		(33 "B.Fab" user "Ref Des/Assembly Bottom")
	)
	(footprint ""
		(layer "F.Cu")
		(at 189.65037 -427.319948 180)
		(property "Reference" "C1797"
			(at 0 0 180)
			(layer "F.SilkS")
			(hide yes)
			(effects
				(font
					(size 1.27 1.27)
				)
			)
		)
		(property "Value" ""
			(at 0 0 180)
			(layer "F.Fab")
			(effects
				(font
					(size 1.27 1.27)
				)
			)
		)
		(duplicate_pad_numbers_are_jumpers no)
		(fp_line
			(start 0.7874 0.4064)
			(end -0.7874 0.4064)
			(stroke
				(width 0.1524)
				(type default)
			)
			(layer "F.SilkS")
		)
		(fp_line
			(start 0.7874 -0.4064)
			(end 0.7874 0.4064)
			(stroke
				(width 0.1524)
				(type default)
			)
			(layer "F.SilkS")
		)
		(fp_line
			(start -0.7874 0.4064)
			(end -0.7874 -0.4064)
			(stroke
				(width 0.1524)
				(type default)
			)
			(layer "F.SilkS")
		)
		(fp_line
			(start -0.7874 -0.4064)
			(end 0.7874 -0.4064)
			(stroke
				(width 0.1524)
				(type default)
			)
			(layer "F.SilkS")
		)
		(fp_line
			(start 0.67945 0.3048)
			(end 0.120396 0.3048)
			(stroke
				(width 0.1)
				(type default)
			)
			(layer "F.Fab")
		)
		(fp_line
			(start 0.67945 -0.3048)
			(end 0.67945 0.3048)
			(stroke
				(width 0.1)
				(type default)
			)
			(layer "F.Fab")
		)
		(fp_line
			(start 0.12065 -0.2794)
			(end 0.12065 -0.3048)
			(stroke
				(width 0.1)
				(type default)
			)
			(layer "F.Fab")
		)
		(fp_line
			(start 0.12065 -0.3048)
			(end 0.67945 -0.3048)
			(stroke
				(width 0.1)
				(type default)
			)
			(layer "F.Fab")
		)
		(fp_line
			(start 0.120396 0.3048)
			(end 0.120396 0.2794)
			(stroke
				(width 0.1)
				(type default)
			)
			(layer "F.Fab")
		)
		(fp_line
			(start 0.120396 0.2794)
			(end -0.12065 0.2794)
			(stroke
				(width 0.1)
				(type default)
			)
			(layer "F.Fab")
		)
		(fp_line
			(start -0.12065 0.3048)
			(end -0.67945 0.3048)
			(stroke
				(width 0.1)
				(type default)
			)
			(layer "F.Fab")
		)
		(fp_line
			(start -0.12065 0.2794)
			(end -0.12065 0.3048)
			(stroke
				(width 0.1)
				(type default)
			)
			(layer "F.Fab")
		)
		(fp_line
			(start -0.12065 -0.2794)
			(end 0.12065 -0.2794)
			(stroke
				(width 0.1)
				(type default)
			)
			(layer "F.Fab")
		)
		(fp_line
			(start -0.12065 -0.305054)
			(end -0.12065 -0.2794)
			(stroke
				(width 0.1)
				(type default)
			)
			(layer "F.Fab")
		)
		(fp_line
			(start -0.67945 0.3048)
			(end -0.67945 -0.305054)
			(stroke
				(width 0.1)
				(type default)
			)
			(layer "F.Fab")
		)
		(fp_line
			(start -0.67945 -0.305054)
			(end -0.12065 -0.305054)
			(stroke
				(width 0.1)
				(type default)
			)
			(layer "F.Fab")
		)
		(pad "1" smd circle
			(at -0.40005 0 180)
			(size 0 0)
			(layers "F.Cu" "F.Mask" "F.Paste")
			(net "PDB_PRSNT_N")
		)
		(pad "2" smd circle
			(at 0.40005 0 180)
			(size 0 0)
			(layers "F.Cu" "F.Mask" "F.Paste")
			(net "GND")
		)
	)
	(footprint ""
		(layer "F.Cu")
		(at 351.806764 -360.934762 90)
		(property "Reference" "C3266"
			(at 0 0 90)
			(layer "F.SilkS")
			(hide yes)
			(effects
				(font
					(size 1.27 1.27)
				)
			)
		)
		(property "Value" ""
			(at 0 0 90)
			(layer "F.Fab")
			(effects
				(font
					(size 1.27 1.27)
				)
			)
		)
		(duplicate_pad_numbers_are_jumpers no)
		(fp_line
			(start 0.7874 -0.4064)
			(end 0.7874 0.4064)
			(stroke
				(width 0.1524)
				(type default)
			)
			(layer "F.SilkS")
		)
		(fp_line
			(start -0.7874 -0.4064)
			(end 0.7874 -0.4064)
			(stroke
				(width 0.1524)
				(type default)
			)
			(layer "F.SilkS")
		)
		(fp_line
			(start 0.7874 0.4064)
			(end -0.7874 0.4064)
			(stroke
				(width 0.1524)
				(type default)
			)
			(layer "F.SilkS")
		)
		(fp_line
			(start -0.7874 0.4064)
			(end -0.7874 -0.4064)
			(stroke
				(width 0.1524)
				(type default)
			)
			(layer "F.SilkS")
		)
		(fp_line
			(start -0.12065 -0.305054)
			(end -0.12065 -0.2794)
			(stroke
				(width 0.1)
				(type default)
			)
			(layer "F.Fab")
		)
		(fp_line
			(start -0.67945 -0.305054)
			(end -0.12065 -0.305054)
			(stroke
				(width 0.1)
				(type default)
			)
			(layer "F.Fab")
		)
		(fp_line
			(start 0.67945 -0.3048)
			(end 0.67945 0.3048)
			(stroke
				(width 0.1)
				(type default)
			)
			(layer "F.Fab")
		)
		(fp_line
			(start 0.12065 -0.3048)
			(end 0.67945 -0.3048)
			(stroke
				(width 0.1)
				(type default)
			)
			(layer "F.Fab")
		)
		(fp_line
			(start 0.12065 -0.2794)
			(end 0.12065 -0.3048)
			(stroke
				(width 0.1)
				(type default)
			)
			(layer "F.Fab")
		)
		(fp_line
			(start -0.12065 -0.2794)
			(end 0.12065 -0.2794)
			(stroke
				(width 0.1)
				(type default)
			)
			(layer "F.Fab")
		)
		(fp_line
			(start 0.120396 0.2794)
			(end -0.12065 0.2794)
			(stroke
				(width 0.1)
				(type default)
			)
			(layer "F.Fab")
		)
		(fp_line
			(start -0.12065 0.2794)
			(end -0.12065 0.3048)
			(stroke
				(width 0.1)
				(type default)
			)
			(layer "F.Fab")
		)
		(fp_line
			(start 0.67945 0.3048)
			(end 0.120396 0.3048)
			(stroke
				(width 0.1)
				(type default)
			)
			(layer "F.Fab")
		)
		(fp_line
			(start 0.120396 0.3048)
			(end 0.120396 0.2794)
			(stroke
				(width 0.1)
				(type default)
			)
			(layer "F.Fab")
		)
		(fp_line
			(start -0.12065 0.3048)
			(end -0.67945 0.3048)
			(stroke
				(width 0.1)
				(type default)
			)
			(layer "F.Fab")
		)
		(fp_line
			(start -0.67945 0.3048)
			(end -0.67945 -0.305054)
			(stroke
				(width 0.1)
				(type default)
			)
			(layer "F.Fab")
		)
		(pad "1" smd circle
			(at -0.40005 0 90)
			(size 0 0)
			(layers "F.Cu" "F.Mask" "F.Paste")
			(net "PWRGD_PVCCIN_CPU0_R")
		)
		(pad "2" smd circle
			(at 0.40005 0 90)
			(size 0 0)
			(layers "F.Cu" "F.Mask" "F.Paste")
			(net "GND")
		)
	)
)
